(kicad_pcb
	(version 20260206)
	(generator "pcbnew")
	(generator_version "10.0")
	(general
		(thickness 1.6)
		(legacy_teardrops no)
	)
	(paper "A4")
	(title_block
		(title "04192023_DAF0TMB3IC0_F0TG_MB_C_brd_V02_OCP.brd")
		(comment 1 "Grand Teton / footprints 6869-6875 of 8354")
	)
	(layers
		(0 "F.Cu" signal "TOP")
		(4 "In1.Cu" signal "GND")
		(6 "In2.Cu" signal "IN1")
		(8 "In3.Cu" signal "GND1")
		(10 "In4.Cu" signal "IN2")
		(12 "In5.Cu" signal "GND2")
		(14 "In6.Cu" signal "IN3")
		(16 "In7.Cu" signal "GND3")
		(18 "In8.Cu" signal "VCC")
		(20 "In9.Cu" signal "VCC1")
		(22 "In10.Cu" signal "GND4")
		(24 "In11.Cu" signal "IN4")
		(26 "In12.Cu" signal "GND5")
		(28 "In13.Cu" signal "IN5")
		(30 "In14.Cu" signal "GND6")
		(32 "In15.Cu" signal "IN6")
		(34 "In16.Cu" signal "GND7")
		(2 "B.Cu" signal "BOTTOM")
		(9 "F.Adhes" user "F.Adhesive")
		(11 "B.Adhes" user "B.Adhesive")
		(13 "F.Paste" user "Package Geometry/Pastemask Top")
		(15 "B.Paste" user "Package Geometry/Pastemask Bottom")
		(5 "F.SilkS" user "Ref Des/Silkscreen Top")
		(7 "B.SilkS" user "Ref Des/Silkscreen Bottom")
		(1 "F.Mask" user "Board Geometry/Soldermask Top")
		(3 "B.Mask" user "Board Geometry/Soldermask Bottom")
		(17 "Dwgs.User" user "User.Drawings")
		(19 "Cmts.User" user "User.Comments")
		(21 "Eco1.User" user "User.Eco1")
		(23 "Eco2.User" user "User.Eco2")
		(25 "Edge.Cuts" user "Board Geometry/Outline")
		(27 "Margin" user)
		(31 "F.CrtYd" user "Package Geometry/Place Bound Top")
		(29 "B.CrtYd" user "Package Geometry/Place Bound Bottom")
		(35 "F.Fab" user "Ref Des/Assembly Top")
		(33 "B.Fab" user "Ref Des/Assembly Bottom")
	)
	(footprint ""
		(layer "B.Cu")
		(at 231.072436 -326.07885)
		(property "Reference" "R1257"
			(at 0 0 0)
			(layer "B.SilkS")
			(hide yes)
			(effects
				(font
					(size 1.27 1.27)
				)
				(justify mirror)
			)
		)
		(property "Value" ""
			(at 0 0 0)
			(layer "B.Fab")
			(effects
				(font
					(size 1.27 1.27)
				)
				(justify mirror)
			)
		)
		(duplicate_pad_numbers_are_jumpers no)
		(fp_line
			(start -0.7874 -0.4064)
			(end -0.7874 0.4064)
			(stroke
				(width 0.1524)
				(type default)
			)
			(layer "B.SilkS")
		)
		(fp_line
			(start -0.7874 0.4064)
			(end 0.7874 0.4064)
			(stroke
				(width 0.1524)
				(type default)
			)
			(layer "B.SilkS")
		)
		(fp_line
			(start 0.7874 -0.4064)
			(end -0.7874 -0.4064)
			(stroke
				(width 0.1524)
				(type default)
			)
			(layer "B.SilkS")
		)
		(fp_line
			(start 0.7874 0.4064)
			(end 0.7874 -0.4064)
			(stroke
				(width 0.1524)
				(type default)
			)
			(layer "B.SilkS")
		)
		(fp_line
			(start -0.67945 -0.3048)
			(end -0.67945 0.3048)
			(stroke
				(width 0.1)
				(type default)
			)
			(layer "B.Fab")
		)
		(fp_line
			(start -0.67945 0.3048)
			(end -0.120396 0.3048)
			(stroke
				(width 0.1)
				(type default)
			)
			(layer "B.Fab")
		)
		(fp_line
			(start -0.12065 -0.3048)
			(end -0.67945 -0.3048)
			(stroke
				(width 0.1)
				(type default)
			)
			(layer "B.Fab")
		)
		(fp_line
			(start -0.12065 -0.2794)
			(end -0.12065 -0.3048)
			(stroke
				(width 0.1)
				(type default)
			)
			(layer "B.Fab")
		)
		(fp_line
			(start -0.120396 0.2794)
			(end 0.12065 0.2794)
			(stroke
				(width 0.1)
				(type default)
			)
			(layer "B.Fab")
		)
		(fp_line
			(start -0.120396 0.3048)
			(end -0.120396 0.2794)
			(stroke
				(width 0.1)
				(type default)
			)
			(layer "B.Fab")
		)
		(fp_line
			(start 0.12065 -0.305054)
			(end 0.12065 -0.2794)
			(stroke
				(width 0.1)
				(type default)
			)
			(layer "B.Fab")
		)
		(fp_line
			(start 0.12065 -0.2794)
			(end -0.12065 -0.2794)
			(stroke
				(width 0.1)
				(type default)
			)
			(layer "B.Fab")
		)
		(fp_line
			(start 0.12065 0.2794)
			(end 0.12065 0.3048)
			(stroke
				(width 0.1)
				(type default)
			)
			(layer "B.Fab")
		)
		(fp_line
			(start 0.12065 0.3048)
			(end 0.67945 0.3048)
			(stroke
				(width 0.1)
				(type default)
			)
			(layer "B.Fab")
		)
		(fp_line
			(start 0.67945 -0.305054)
			(end 0.12065 -0.305054)
			(stroke
				(width 0.1)
				(type default)
			)
			(layer "B.Fab")
		)
		(fp_line
			(start 0.67945 0.3048)
			(end 0.67945 -0.305054)
			(stroke
				(width 0.1)
				(type default)
			)
			(layer "B.Fab")
		)
		(pad "1" smd rect
			(at 0.40005 0)
			(size 0.4572 0.508)
			(layers "B.Cu" "B.Mask" "B.Paste")
			(net "P1V8_CPU1_RT_1D_ADC")
		)
		(pad "2" smd rect
			(at -0.40005 0)
			(size 0.4572 0.508)
			(layers "B.Cu" "B.Mask" "B.Paste")
			(net "P1V8_CPU1_RT_1D_ADC_TIC")
		)
	)
	(footprint ""
		(layer "B.Cu")
		(at 359.421176 -179.67452 90)
		(property "Reference" "PC575_5"
			(at 0 0 90)
			(layer "B.SilkS")
			(hide yes)
			(effects
				(font
					(size 1.27 1.27)
				)
				(justify mirror)
			)
		)
		(property "Value" ""
			(at 0 0 90)
			(layer "B.Fab")
			(effects
				(font
					(size 1.27 1.27)
				)
				(justify mirror)
			)
		)
		(duplicate_pad_numbers_are_jumpers no)
		(fp_line
			(start 1.524 -0.762)
			(end -1.524 -0.762)
			(stroke
				(width 0.1524)
				(type default)
			)
			(layer "B.SilkS")
		)
		(fp_line
			(start -1.524 -0.762)
			(end -1.524 0.762)
			(stroke
				(width 0.1524)
				(type default)
			)
			(layer "B.SilkS")
		)
		(fp_line
			(start 1.524 0.762)
			(end 1.524 -0.762)
			(stroke
				(width 0.1524)
				(type default)
			)
			(layer "B.SilkS")
		)
		(fp_line
			(start -1.524 0.762)
			(end 1.524 0.762)
			(stroke
				(width 0.1524)
				(type default)
			)
			(layer "B.SilkS")
		)
		(fp_line
			(start 1.1049 -0.724916)
			(end 1.1049 0.724916)
			(stroke
				(width 0.1)
				(type default)
			)
			(layer "B.Fab")
		)
		(fp_line
			(start -1.1049 -0.724916)
			(end 1.1049 -0.724916)
			(stroke
				(width 0.1)
				(type default)
			)
			(layer "B.Fab")
		)
		(fp_line
			(start 1.1049 0.724916)
			(end -1.1049 0.724916)
			(stroke
				(width 0.1)
				(type default)
			)
			(layer "B.Fab")
		)
		(fp_line
			(start -1.1049 0.724916)
			(end -1.1049 -0.724916)
			(stroke
				(width 0.1)
				(type default)
			)
			(layer "B.Fab")
		)
		(pad "1" smd rect
			(at 0.889 0 90)
			(size 1.016 1.27)
			(layers "B.Cu" "B.Mask" "B.Paste")
			(net "PVDDCR_CPU0_P0")
		)
		(pad "2" smd rect
			(at -0.889 0 90)
			(size 1.016 1.27)
			(layers "B.Cu" "B.Mask" "B.Paste")
			(net "GND")
		)
	)
	(footprint ""
		(layer "B.Cu")
		(at 380.282958 -205.902052 -90)
		(property "Reference" "R986"
			(at 0 0 90)
			(layer "B.SilkS")
			(hide yes)
			(effects
				(font
					(size 1.27 1.27)
				)
				(justify mirror)
			)
		)
		(property "Value" ""
			(at 0 0 90)
			(layer "B.Fab")
			(effects
				(font
					(size 1.27 1.27)
				)
				(justify mirror)
			)
		)
		(duplicate_pad_numbers_are_jumpers no)
		(fp_line
			(start -0.7874 0.4064)
			(end 0.7874 0.4064)
			(stroke
				(width 0.1524)
				(type default)
			)
			(layer "B.SilkS")
		)
		(fp_line
			(start 0.7874 0.4064)
			(end 0.7874 -0.4064)
			(stroke
				(width 0.1524)
				(type default)
			)
			(layer "B.SilkS")
		)
		(fp_line
			(start -0.7874 -0.4064)
			(end -0.7874 0.4064)
			(stroke
				(width 0.1524)
				(type default)
			)
			(layer "B.SilkS")
		)
		(fp_line
			(start 0.7874 -0.4064)
			(end -0.7874 -0.4064)
			(stroke
				(width 0.1524)
				(type default)
			)
			(layer "B.SilkS")
		)
		(fp_line
			(start -0.67945 0.3048)
			(end -0.120396 0.3048)
			(stroke
				(width 0.1)
				(type default)
			)
			(layer "B.Fab")
		)
		(fp_line
			(start -0.120396 0.3048)
			(end -0.120396 0.2794)
			(stroke
				(width 0.1)
				(type default)
			)
			(layer "B.Fab")
		)
		(fp_line
			(start 0.12065 0.3048)
			(end 0.67945 0.3048)
			(stroke
				(width 0.1)
				(type default)
			)
			(layer "B.Fab")
		)
		(fp_line
			(start 0.67945 0.3048)
			(end 0.67945 -0.305054)
			(stroke
				(width 0.1)
				(type default)
			)
			(layer "B.Fab")
		)
		(fp_line
			(start -0.120396 0.2794)
			(end 0.12065 0.2794)
			(stroke
				(width 0.1)
				(type default)
			)
			(layer "B.Fab")
		)
		(fp_line
			(start 0.12065 0.2794)
			(end 0.12065 0.3048)
			(stroke
				(width 0.1)
				(type default)
			)
			(layer "B.Fab")
		)
		(fp_line
			(start -0.12065 -0.2794)
			(end -0.12065 -0.3048)
			(stroke
				(width 0.1)
				(type default)
			)
			(layer "B.Fab")
		)
		(fp_line
			(start 0.12065 -0.2794)
			(end -0.12065 -0.2794)
			(stroke
				(width 0.1)
				(type default)
			)
			(layer "B.Fab")
		)
		(fp_line
			(start -0.67945 -0.3048)
			(end -0.67945 0.3048)
			(stroke
				(width 0.1)
				(type default)
			)
			(layer "B.Fab")
		)
		(fp_line
			(start -0.12065 -0.3048)
			(end -0.67945 -0.3048)
			(stroke
				(width 0.1)
				(type default)
			)
			(layer "B.Fab")
		)
		(fp_line
			(start 0.12065 -0.305054)
			(end 0.12065 -0.2794)
			(stroke
				(width 0.1)
				(type default)
			)
			(layer "B.Fab")
		)
		(fp_line
			(start 0.67945 -0.305054)
			(end 0.12065 -0.305054)
			(stroke
				(width 0.1)
				(type default)
			)
			(layer "B.Fab")
		)
		(pad "1" smd rect
			(at 0.40005 0 270)
			(size 0.4572 0.508)
			(layers "B.Cu" "B.Mask" "B.Paste")
			(net "I3C_1_SPD_DDRGL_CPU0_R_SCL")
		)
		(pad "2" smd rect
			(at -0.40005 0 270)
			(size 0.4572 0.508)
			(layers "B.Cu" "B.Mask" "B.Paste")
			(net "I3C_SPD_DDRGL_CPU0_BYPASS_SCL")
		)
	)
	(footprint ""
		(layer "B.Cu")
		(at 232.537 -339.725 90)
		(property "Reference" "R6764"
			(at 0 0 90)
			(layer "B.SilkS")
			(hide yes)
			(effects
				(font
					(size 1.27 1.27)
				)
				(justify mirror)
			)
		)
		(property "Value" ""
			(at 0 0 90)
			(layer "B.Fab")
			(effects
				(font
					(size 1.27 1.27)
				)
				(justify mirror)
			)
		)
		(duplicate_pad_numbers_are_jumpers no)
		(fp_line
			(start 0.32512 -0.175006)
			(end -0.32512 -0.175006)
			(stroke
				(width 0.1)
				(type default)
			)
			(layer "B.Fab")
		)
		(fp_line
			(start -0.32512 -0.175006)
			(end -0.32512 0.175006)
			(stroke
				(width 0.1)
				(type default)
			)
			(layer "B.Fab")
		)
		(fp_line
			(start 0.32512 0.175006)
			(end 0.32512 -0.175006)
			(stroke
				(width 0.1)
				(type default)
			)
			(layer "B.Fab")
		)
		(fp_line
			(start -0.32512 0.175006)
			(end 0.32512 0.175006)
			(stroke
				(width 0.1)
				(type default)
			)
			(layer "B.Fab")
		)
		(pad "1" smd rect
			(at 0.2667 0 270)
			(size 0.3048 0.381)
			(layers "B.Cu" "B.Mask" "B.Paste")
			(net "P1V8_CPU0_RT_1D")
		)
		(pad "2" smd rect
			(at -0.2667 0 90)
			(size 0.3048 0.381)
			(layers "B.Cu" "B.Mask" "B.Paste")
			(net "SMB_RT_CPU0_P1_R_SDA")
		)
	)
	(footprint ""
		(layer "B.Cu")
		(at 187.055506 -126.833376 -90)
		(property "Reference" "R161"
			(at 0 0 90)
			(layer "B.SilkS")
			(hide yes)
			(effects
				(font
					(size 1.27 1.27)
				)
				(justify mirror)
			)
		)
		(property "Value" ""
			(at 0 0 90)
			(layer "B.Fab")
			(effects
				(font
					(size 1.27 1.27)
				)
				(justify mirror)
			)
		)
		(duplicate_pad_numbers_are_jumpers no)
		(fp_line
			(start -0.7874 0.4064)
			(end 0.7874 0.4064)
			(stroke
				(width 0.1524)
				(type default)
			)
			(layer "B.SilkS")
		)
		(fp_line
			(start 0.7874 0.4064)
			(end 0.7874 -0.4064)
			(stroke
				(width 0.1524)
				(type default)
			)
			(layer "B.SilkS")
		)
		(fp_line
			(start -0.7874 -0.4064)
			(end -0.7874 0.4064)
			(stroke
				(width 0.1524)
				(type default)
			)
			(layer "B.SilkS")
		)
		(fp_line
			(start 0.7874 -0.4064)
			(end -0.7874 -0.4064)
			(stroke
				(width 0.1524)
				(type default)
			)
			(layer "B.SilkS")
		)
		(fp_line
			(start -0.67945 0.3048)
			(end -0.120396 0.3048)
			(stroke
				(width 0.1)
				(type default)
			)
			(layer "B.Fab")
		)
		(fp_line
			(start -0.120396 0.3048)
			(end -0.120396 0.2794)
			(stroke
				(width 0.1)
				(type default)
			)
			(layer "B.Fab")
		)
		(fp_line
			(start 0.12065 0.3048)
			(end 0.67945 0.3048)
			(stroke
				(width 0.1)
				(type default)
			)
			(layer "B.Fab")
		)
		(fp_line
			(start 0.67945 0.3048)
			(end 0.67945 -0.305054)
			(stroke
				(width 0.1)
				(type default)
			)
			(layer "B.Fab")
		)
		(fp_line
			(start -0.120396 0.2794)
			(end 0.12065 0.2794)
			(stroke
				(width 0.1)
				(type default)
			)
			(layer "B.Fab")
		)
		(fp_line
			(start 0.12065 0.2794)
			(end 0.12065 0.3048)
			(stroke
				(width 0.1)
				(type default)
			)
			(layer "B.Fab")
		)
		(fp_line
			(start -0.12065 -0.2794)
			(end -0.12065 -0.3048)
			(stroke
				(width 0.1)
				(type default)
			)
			(layer "B.Fab")
		)
		(fp_line
			(start 0.12065 -0.2794)
			(end -0.12065 -0.2794)
			(stroke
				(width 0.1)
				(type default)
			)
			(layer "B.Fab")
		)
		(fp_line
			(start -0.67945 -0.3048)
			(end -0.67945 0.3048)
			(stroke
				(width 0.1)
				(type default)
			)
			(layer "B.Fab")
		)
		(fp_line
			(start -0.12065 -0.3048)
			(end -0.67945 -0.3048)
			(stroke
				(width 0.1)
				(type default)
			)
			(layer "B.Fab")
		)
		(fp_line
			(start 0.12065 -0.305054)
			(end 0.12065 -0.2794)
			(stroke
				(width 0.1)
				(type default)
			)
			(layer "B.Fab")
		)
		(fp_line
			(start 0.67945 -0.305054)
			(end 0.12065 -0.305054)
			(stroke
				(width 0.1)
				(type default)
			)
			(layer "B.Fab")
		)
		(pad "1" smd circle
			(at 0.40005 0 90)
			(size 0 0)
			(layers "B.Cu" "B.Mask" "B.Paste")
			(net "CPU1_JTAG_BUF_R_OE")
		)
		(pad "2" smd circle
			(at -0.40005 0 90)
			(size 0 0)
			(layers "B.Cu" "B.Mask" "B.Paste")
			(net "CPU1_JTAG_BUF_OE")
		)
	)
	(footprint ""
		(layer "B.Cu")
		(at 214.122 -334.01)
		(property "Reference" "R6813"
			(at 0 0 0)
			(layer "B.SilkS")
			(hide yes)
			(effects
				(font
					(size 1.27 1.27)
				)
				(justify mirror)
			)
		)
		(property "Value" ""
			(at 0 0 0)
			(layer "B.Fab")
			(effects
				(font
					(size 1.27 1.27)
				)
				(justify mirror)
			)
		)
		(duplicate_pad_numbers_are_jumpers no)
		(fp_line
			(start -0.32512 -0.175006)
			(end -0.32512 0.175006)
			(stroke
				(width 0.1)
				(type default)
			)
			(layer "B.Fab")
		)
		(fp_line
			(start -0.32512 0.175006)
			(end 0.32512 0.175006)
			(stroke
				(width 0.1)
				(type default)
			)
			(layer "B.Fab")
		)
		(fp_line
			(start 0.32512 -0.175006)
			(end -0.32512 -0.175006)
			(stroke
				(width 0.1)
				(type default)
			)
			(layer "B.Fab")
		)
		(fp_line
			(start 0.32512 0.175006)
			(end 0.32512 -0.175006)
			(stroke
				(width 0.1)
				(type default)
			)
			(layer "B.Fab")
		)
		(pad "1" smd rect
			(at 0.2667 0 180)
			(size 0.3048 0.381)
			(layers "B.Cu" "B.Mask" "B.Paste")
			(net "SMB_RT_CPU1_P0_R_SDA")
		)
		(pad "2" smd rect
			(at -0.2667 0)
			(size 0.3048 0.381)
			(layers "B.Cu" "B.Mask" "B.Paste")
			(net "SMB_RT_CPU1_P0_R2_SDA")
		)
	)
	(footprint ""
		(layer "B.Cu")
		(at 180.721 -100.294948 90)
		(property "Reference" "R278"
			(at 0 0 90)
			(layer "B.SilkS")
			(hide yes)
			(effects
				(font
					(size 1.27 1.27)
				)
				(justify mirror)
			)
		)
		(property "Value" ""
			(at 0 0 90)
			(layer "B.Fab")
			(effects
				(font
					(size 1.27 1.27)
				)
				(justify mirror)
			)
		)
		(duplicate_pad_numbers_are_jumpers no)
		(fp_line
			(start 0.7874 -0.4064)
			(end -0.7874 -0.4064)
			(stroke
				(width 0.1524)
				(type default)
			)
			(layer "B.SilkS")
		)
		(fp_line
			(start -0.7874 -0.4064)
			(end -0.7874 0.4064)
			(stroke
				(width 0.1524)
				(type default)
			)
			(layer "B.SilkS")
		)
		(fp_line
			(start 0.7874 0.4064)
			(end 0.7874 -0.4064)
			(stroke
				(width 0.1524)
				(type default)
			)
			(layer "B.SilkS")
		)
		(fp_line
			(start -0.7874 0.4064)
			(end 0.7874 0.4064)
			(stroke
				(width 0.1524)
				(type default)
			)
			(layer "B.SilkS")
		)
		(fp_line
			(start 0.67945 -0.305054)
			(end 0.12065 -0.305054)
			(stroke
				(width 0.1)
				(type default)
			)
			(layer "B.Fab")
		)
		(fp_line
			(start 0.12065 -0.305054)
			(end 0.12065 -0.2794)
			(stroke
				(width 0.1)
				(type default)
			)
			(layer "B.Fab")
		)
		(fp_line
			(start -0.12065 -0.3048)
			(end -0.67945 -0.3048)
			(stroke
				(width 0.1)
				(type default)
			)
			(layer "B.Fab")
		)
		(fp_line
			(start -0.67945 -0.3048)
			(end -0.67945 0.3048)
			(stroke
				(width 0.1)
				(type default)
			)
			(layer "B.Fab")
		)
		(fp_line
			(start 0.12065 -0.2794)
			(end -0.12065 -0.2794)
			(stroke
				(width 0.1)
				(type default)
			)
			(layer "B.Fab")
		)
		(fp_line
			(start -0.12065 -0.2794)
			(end -0.12065 -0.3048)
			(stroke
				(width 0.1)
				(type default)
			)
			(layer "B.Fab")
		)
		(fp_line
			(start 0.12065 0.2794)
			(end 0.12065 0.3048)
			(stroke
				(width 0.1)
				(type default)
			)
			(layer "B.Fab")
		)
		(fp_line
			(start -0.120396 0.2794)
			(end 0.12065 0.2794)
			(stroke
				(width 0.1)
				(type default)
			)
			(layer "B.Fab")
		)
		(fp_line
			(start 0.67945 0.3048)
			(end 0.67945 -0.305054)
			(stroke
				(width 0.1)
				(type default)
			)
			(layer "B.Fab")
		)
		(fp_line
			(start 0.12065 0.3048)
			(end 0.67945 0.3048)
			(stroke
				(width 0.1)
				(type default)
			)
			(layer "B.Fab")
		)
		(fp_line
			(start -0.120396 0.3048)
			(end -0.120396 0.2794)
			(stroke
				(width 0.1)
				(type default)
			)
			(layer "B.Fab")
		)
		(fp_line
			(start -0.67945 0.3048)
			(end -0.120396 0.3048)
			(stroke
				(width 0.1)
				(type default)
			)
			(layer "B.Fab")
		)
		(pad "1" smd circle
			(at 0.40005 0 270)
			(size 0 0)
			(layers "B.Cu" "B.Mask" "B.Paste")
			(net "FM_PVDD11_S3_P1_OCP_N")
		)
		(pad "2" smd circle
			(at -0.40005 0 270)
			(size 0 0)
			(layers "B.Cu" "B.Mask" "B.Paste")
			(net "PVDD11_S3_P1_OCP_N")
		)
	)
)
